(kicad_pcb
	(version 20260206)
	(generator "pcbnew")
	(generator_version "10.0")
	(general
		(thickness 1.6)
		(legacy_teardrops no)
	)
	(paper "A4")
	(title_block
		(title "12092022_DA0F0TFB6D0_F0T_FAN_BOARD_MP5048_D_brd_v02_OCP.brd")
		(comment 1 "Grand Teton / footprints 416-420 of 924")
	)
	(layers
		(0 "F.Cu" signal "TOP")
		(4 "In1.Cu" signal "GND")
		(6 "In2.Cu" signal "IN1")
		(8 "In3.Cu" signal "IN2")
		(10 "In4.Cu" signal "GND1")
		(2 "B.Cu" signal "BOTTOM")
		(9 "F.Adhes" user "F.Adhesive")
		(11 "B.Adhes" user "B.Adhesive")
		(13 "F.Paste" user "Package Geometry/Pastemask Top")
		(15 "B.Paste" user "Package Geometry/Pastemask Bottom")
		(5 "F.SilkS" user "Ref Des/Silkscreen Top")
		(7 "B.SilkS" user "Ref Des/Silkscreen Bottom")
		(1 "F.Mask" user "Board Geometry/Soldermask Top")
		(3 "B.Mask" user "Board Geometry/Soldermask Bottom")
		(17 "Dwgs.User" user "User.Drawings")
		(19 "Cmts.User" user "User.Comments")
		(21 "Eco1.User" user "User.Eco1")
		(23 "Eco2.User" user "User.Eco2")
		(25 "Edge.Cuts" user "Board Geometry/Outline")
		(27 "Margin" user)
		(31 "F.CrtYd" user "Package Geometry/Place Bound Top")
		(29 "B.CrtYd" user "Package Geometry/Place Bound Bottom")
		(35 "F.Fab" user "Ref Des/Assembly Top")
		(33 "B.Fab" user "Ref Des/Assembly Bottom")
	)
	(footprint ""
		(layer "F.Cu")
		(at 14.478 -28.877768 180)
		(property "Reference" "D240"
			(at 5.0292 -0.088138 0)
			(unlocked yes)
			(layer "F.SilkS")
			(effects
				(font
					(size 0.7874 0.5842)
					(thickness 0.1524)
				)
				(justify left)
			)
		)
		(property "Value" ""
			(at 0 0 180)
			(layer "F.Fab")
			(effects
				(font
					(size 1.27 1.27)
				)
			)
		)
		(duplicate_pad_numbers_are_jumpers no)
		(fp_line
			(start 0.94488 0.450088)
			(end 0.94488 -0.450088)
			(stroke
				(width 0.1524)
				(type default)
			)
			(layer "F.SilkS")
		)
		(fp_line
			(start 0.94488 -0.450088)
			(end -0.854964 -0.450088)
			(stroke
				(width 0.1524)
				(type default)
			)
			(layer "F.SilkS")
		)
		(fp_line
			(start 0.870458 -0.2794)
			(end 0.845058 0.4064)
			(stroke
				(width 0.1524)
				(type default)
			)
			(layer "F.SilkS")
		)
		(fp_line
			(start 0.845058 0.4064)
			(end 0.845058 -0.381)
			(stroke
				(width 0.1524)
				(type default)
			)
			(layer "F.SilkS")
		)
		(fp_line
			(start -0.854964 0.450088)
			(end 0.925068 0.450088)
			(stroke
				(width 0.1524)
				(type default)
			)
			(layer "F.SilkS")
		)
		(fp_line
			(start -0.854964 -0.450088)
			(end -0.854964 0.450088)
			(stroke
				(width 0.1524)
				(type default)
			)
			(layer "F.SilkS")
		)
		(fp_line
			(start 0.54991 0.350012)
			(end 0.54991 -0.350012)
			(stroke
				(width 0.1)
				(type default)
			)
			(layer "F.Fab")
		)
		(fp_line
			(start 0.54991 -0.350012)
			(end -0.54991 -0.350012)
			(stroke
				(width 0.1)
				(type default)
			)
			(layer "F.Fab")
		)
		(fp_line
			(start -0.54991 0.350012)
			(end 0.54991 0.350012)
			(stroke
				(width 0.1)
				(type default)
			)
			(layer "F.Fab")
		)
		(fp_line
			(start -0.54991 -0.350012)
			(end -0.54991 0.350012)
			(stroke
				(width 0.1)
				(type default)
			)
			(layer "F.Fab")
		)
		(fp_text user "-"
			(at 2.159 0.935482 0)
			(unlocked yes)
			(layer "F.SilkS")
			(effects
				(font
					(size 1.905 1.4224)
					(thickness 0.1524)
				)
				(justify left)
			)
		)
		(fp_text user "+"
			(at -1.016 0.300482 0)
			(unlocked yes)
			(layer "F.SilkS")
			(effects
				(font
					(size 1.905 1.4224)
					(thickness 0.1524)
				)
				(justify left)
			)
		)
		(fp_text user "-"
			(at 2.48539 0.239014 0)
			(unlocked yes)
			(layer "F.Fab")
			(effects
				(font
					(size 1.905 1.4224)
					(thickness 0.1524)
				)
				(justify left)
			)
		)
		(fp_text user "+"
			(at -0.808228 0.239014 0)
			(unlocked yes)
			(layer "F.Fab")
			(effects
				(font
					(size 1.905 1.4224)
					(thickness 0.1524)
				)
				(justify left)
			)
		)
		(pad "A" smd rect
			(at -0.424942 0 180)
			(size 0.5588 0.6096)
			(layers "F.Cu" "F.Mask" "F.Paste")
			(net "GND")
		)
		(pad "C" smd rect
			(at 0.424942 0)
			(size 0.5588 0.6096)
			(layers "F.Cu" "F.Mask" "F.Paste")
			(net "FAN_4_OK_R_LED_N")
		)
	)
	(footprint ""
		(layer "F.Cu")
		(at 27.686 -124.206 -90)
		(property "Reference" "R5679"
			(at 0 0 270)
			(layer "F.SilkS")
			(hide yes)
			(effects
				(font
					(size 1.27 1.27)
				)
			)
		)
		(property "Value" ""
			(at 0 0 270)
			(layer "F.Fab")
			(effects
				(font
					(size 1.27 1.27)
				)
			)
		)
		(duplicate_pad_numbers_are_jumpers no)
		(fp_line
			(start -0.7874 0.4064)
			(end -0.7874 -0.4064)
			(stroke
				(width 0.1524)
				(type default)
			)
			(layer "F.SilkS")
		)
		(fp_line
			(start 0.7874 0.4064)
			(end -0.7874 0.4064)
			(stroke
				(width 0.1524)
				(type default)
			)
			(layer "F.SilkS")
		)
		(fp_line
			(start -0.7874 -0.4064)
			(end 0.7874 -0.4064)
			(stroke
				(width 0.1524)
				(type default)
			)
			(layer "F.SilkS")
		)
		(fp_line
			(start 0.7874 -0.4064)
			(end 0.7874 0.4064)
			(stroke
				(width 0.1524)
				(type default)
			)
			(layer "F.SilkS")
		)
		(fp_line
			(start -0.67945 0.3048)
			(end -0.67945 -0.305054)
			(stroke
				(width 0.1)
				(type default)
			)
			(layer "F.Fab")
		)
		(fp_line
			(start -0.12065 0.3048)
			(end -0.67945 0.3048)
			(stroke
				(width 0.1)
				(type default)
			)
			(layer "F.Fab")
		)
		(fp_line
			(start 0.120396 0.3048)
			(end 0.120396 0.2794)
			(stroke
				(width 0.1)
				(type default)
			)
			(layer "F.Fab")
		)
		(fp_line
			(start 0.67945 0.3048)
			(end 0.120396 0.3048)
			(stroke
				(width 0.1)
				(type default)
			)
			(layer "F.Fab")
		)
		(fp_line
			(start -0.12065 0.2794)
			(end -0.12065 0.3048)
			(stroke
				(width 0.1)
				(type default)
			)
			(layer "F.Fab")
		)
		(fp_line
			(start 0.120396 0.2794)
			(end -0.12065 0.2794)
			(stroke
				(width 0.1)
				(type default)
			)
			(layer "F.Fab")
		)
		(fp_line
			(start -0.12065 -0.2794)
			(end 0.12065 -0.2794)
			(stroke
				(width 0.1)
				(type default)
			)
			(layer "F.Fab")
		)
		(fp_line
			(start 0.12065 -0.2794)
			(end 0.12065 -0.3048)
			(stroke
				(width 0.1)
				(type default)
			)
			(layer "F.Fab")
		)
		(fp_line
			(start 0.12065 -0.3048)
			(end 0.67945 -0.3048)
			(stroke
				(width 0.1)
				(type default)
			)
			(layer "F.Fab")
		)
		(fp_line
			(start 0.67945 -0.3048)
			(end 0.67945 0.3048)
			(stroke
				(width 0.1)
				(type default)
			)
			(layer "F.Fab")
		)
		(fp_line
			(start -0.67945 -0.305054)
			(end -0.12065 -0.305054)
			(stroke
				(width 0.1)
				(type default)
			)
			(layer "F.Fab")
		)
		(fp_line
			(start -0.12065 -0.305054)
			(end -0.12065 -0.2794)
			(stroke
				(width 0.1)
				(type default)
			)
			(layer "F.Fab")
		)
		(pad "1" smd rect
			(at -0.40005 0 90)
			(size 0.4572 0.508)
			(layers "F.Cu" "F.Mask" "F.Paste")
			(net "U317_FAN FS_N")
		)
		(pad "2" smd rect
			(at 0.40005 0 90)
			(size 0.4572 0.508)
			(layers "F.Cu" "F.Mask" "F.Paste")
			(net "U317_FAN FAIL_N")
		)
	)
	(footprint ""
		(layer "F.Cu")
		(at 42.037 -179.324 180)
		(property "Reference" "R512"
			(at 0 0 180)
			(layer "F.SilkS")
			(hide yes)
			(effects
				(font
					(size 1.27 1.27)
				)
			)
		)
		(property "Value" ""
			(at 0 0 180)
			(layer "F.Fab")
			(effects
				(font
					(size 1.27 1.27)
				)
			)
		)
		(duplicate_pad_numbers_are_jumpers no)
		(fp_line
			(start 0.7874 0.4064)
			(end -0.7874 0.4064)
			(stroke
				(width 0.1524)
				(type default)
			)
			(layer "F.SilkS")
		)
		(fp_line
			(start 0.7874 -0.4064)
			(end 0.7874 0.4064)
			(stroke
				(width 0.1524)
				(type default)
			)
			(layer "F.SilkS")
		)
		(fp_line
			(start -0.7874 0.4064)
			(end -0.7874 -0.4064)
			(stroke
				(width 0.1524)
				(type default)
			)
			(layer "F.SilkS")
		)
		(fp_line
			(start -0.7874 -0.4064)
			(end 0.7874 -0.4064)
			(stroke
				(width 0.1524)
				(type default)
			)
			(layer "F.SilkS")
		)
		(fp_line
			(start 0.67945 0.3048)
			(end 0.120396 0.3048)
			(stroke
				(width 0.1)
				(type default)
			)
			(layer "F.Fab")
		)
		(fp_line
			(start 0.67945 -0.3048)
			(end 0.67945 0.3048)
			(stroke
				(width 0.1)
				(type default)
			)
			(layer "F.Fab")
		)
		(fp_line
			(start 0.12065 -0.2794)
			(end 0.12065 -0.3048)
			(stroke
				(width 0.1)
				(type default)
			)
			(layer "F.Fab")
		)
		(fp_line
			(start 0.12065 -0.3048)
			(end 0.67945 -0.3048)
			(stroke
				(width 0.1)
				(type default)
			)
			(layer "F.Fab")
		)
		(fp_line
			(start 0.120396 0.3048)
			(end 0.120396 0.2794)
			(stroke
				(width 0.1)
				(type default)
			)
			(layer "F.Fab")
		)
		(fp_line
			(start 0.120396 0.2794)
			(end -0.12065 0.2794)
			(stroke
				(width 0.1)
				(type default)
			)
			(layer "F.Fab")
		)
		(fp_line
			(start -0.12065 0.3048)
			(end -0.67945 0.3048)
			(stroke
				(width 0.1)
				(type default)
			)
			(layer "F.Fab")
		)
		(fp_line
			(start -0.12065 0.2794)
			(end -0.12065 0.3048)
			(stroke
				(width 0.1)
				(type default)
			)
			(layer "F.Fab")
		)
		(fp_line
			(start -0.12065 -0.2794)
			(end 0.12065 -0.2794)
			(stroke
				(width 0.1)
				(type default)
			)
			(layer "F.Fab")
		)
		(fp_line
			(start -0.12065 -0.305054)
			(end -0.12065 -0.2794)
			(stroke
				(width 0.1)
				(type default)
			)
			(layer "F.Fab")
		)
		(fp_line
			(start -0.67945 0.3048)
			(end -0.67945 -0.305054)
			(stroke
				(width 0.1)
				(type default)
			)
			(layer "F.Fab")
		)
		(fp_line
			(start -0.67945 -0.305054)
			(end -0.12065 -0.305054)
			(stroke
				(width 0.1)
				(type default)
			)
			(layer "F.Fab")
		)
		(pad "1" smd circle
			(at -0.40005 0 180)
			(size 0 0)
			(layers "F.Cu" "F.Mask" "F.Paste")
			(net "P3V3_AUX")
		)
		(pad "2" smd circle
			(at 0.40005 0 180)
			(size 0 0)
			(layers "F.Cu" "F.Mask" "F.Paste")
			(net "P52V_FAN_3_BUFF_EN")
		)
	)
	(footprint ""
		(layer "F.Cu")
		(at 15.377922 -288.5821 180)
		(property "Reference" "D142"
			(at 5.217922 -0.95377 0)
			(unlocked yes)
			(layer "F.SilkS")
			(effects
				(font
					(size 0.7874 0.5842)
					(thickness 0.1524)
				)
				(justify left)
			)
		)
		(property "Value" ""
			(at 0 0 180)
			(layer "F.Fab")
			(effects
				(font
					(size 1.27 1.27)
				)
			)
		)
		(duplicate_pad_numbers_are_jumpers no)
		(fp_line
			(start 2.032 0.7112)
			(end -1.651 0.7112)
			(stroke
				(width 0.1524)
				(type default)
			)
			(layer "F.SilkS")
		)
		(fp_line
			(start 2.032 -0.7112)
			(end 2.032 0.7112)
			(stroke
				(width 0.1524)
				(type default)
			)
			(layer "F.SilkS")
		)
		(fp_line
			(start 1.905 -0.6858)
			(end 1.905 0.6858)
			(stroke
				(width 0.1524)
				(type default)
			)
			(layer "F.SilkS")
		)
		(fp_line
			(start 1.778 0.6858)
			(end 1.778 -0.6858)
			(stroke
				(width 0.1524)
				(type default)
			)
			(layer "F.SilkS")
		)
		(fp_line
			(start 1.651 -0.6858)
			(end 1.651 0.6858)
			(stroke
				(width 0.1524)
				(type default)
			)
			(layer "F.SilkS")
		)
		(fp_line
			(start 0.299974 -0.500126)
			(end 0.299974 0.500126)
			(stroke
				(width 0.1524)
				(type default)
			)
			(layer "F.SilkS")
		)
		(fp_line
			(start 0.199898 0)
			(end -0.299974 -0.500126)
			(stroke
				(width 0.1524)
				(type default)
			)
			(layer "F.SilkS")
		)
		(fp_line
			(start -0.299974 0.500126)
			(end 0.199898 0)
			(stroke
				(width 0.1524)
				(type default)
			)
			(layer "F.SilkS")
		)
		(fp_line
			(start -0.299974 -0.500126)
			(end -0.299974 0.500126)
			(stroke
				(width 0.1524)
				(type default)
			)
			(layer "F.SilkS")
		)
		(fp_line
			(start -1.651 0.7112)
			(end -1.651 -0.7112)
			(stroke
				(width 0.1524)
				(type default)
			)
			(layer "F.SilkS")
		)
		(fp_line
			(start -1.651 -0.7112)
			(end 2.032 -0.7112)
			(stroke
				(width 0.1524)
				(type default)
			)
			(layer "F.SilkS")
		)
		(fp_line
			(start 1.35001 0.175006)
			(end 0.899922 0.175006)
			(stroke
				(width 0.1)
				(type default)
			)
			(layer "F.Fab")
		)
		(fp_line
			(start 1.35001 -0.225044)
			(end 1.35001 0.175006)
			(stroke
				(width 0.1)
				(type default)
			)
			(layer "F.Fab")
		)
		(fp_line
			(start 0.899922 0.700024)
			(end -0.899922 0.700024)
			(stroke
				(width 0.1)
				(type default)
			)
			(layer "F.Fab")
		)
		(fp_line
			(start 0.899922 0.175006)
			(end 0.899922 0.700024)
			(stroke
				(width 0.1)
				(type default)
			)
			(layer "F.Fab")
		)
		(fp_line
			(start 0.899922 -0.225044)
			(end 1.35001 -0.225044)
			(stroke
				(width 0.1)
				(type default)
			)
			(layer "F.Fab")
		)
		(fp_line
			(start 0.899922 -0.700024)
			(end 0.899922 -0.225044)
			(stroke
				(width 0.1)
				(type default)
			)
			(layer "F.Fab")
		)
		(fp_line
			(start 0.299974 -0.500126)
			(end 0.299974 0.500126)
			(stroke
				(width 0.1)
				(type default)
			)
			(layer "F.Fab")
		)
		(fp_line
			(start 0.199898 0)
			(end -0.299974 -0.500126)
			(stroke
				(width 0.1)
				(type default)
			)
			(layer "F.Fab")
		)
		(fp_line
			(start -0.299974 0.500126)
			(end 0.199898 0)
			(stroke
				(width 0.1)
				(type default)
			)
			(layer "F.Fab")
		)
		(fp_line
			(start -0.299974 -0.500126)
			(end -0.299974 0.500126)
			(stroke
				(width 0.1)
				(type default)
			)
			(layer "F.Fab")
		)
		(fp_line
			(start -0.899922 0.700024)
			(end -0.899922 0.175006)
			(stroke
				(width 0.1)
				(type default)
			)
			(layer "F.Fab")
		)
		(fp_line
			(start -0.899922 0.175006)
			(end -1.35001 0.175006)
			(stroke
				(width 0.1)
				(type default)
			)
			(layer "F.Fab")
		)
		(fp_line
			(start -0.899922 -0.225044)
			(end -0.899922 -0.700024)
			(stroke
				(width 0.1)
				(type default)
			)
			(layer "F.Fab")
		)
		(fp_line
			(start -0.899922 -0.700024)
			(end 0.899922 -0.700024)
			(stroke
				(width 0.1)
				(type default)
			)
			(layer "F.Fab")
		)
		(fp_line
			(start -1.35001 0.175006)
			(end -1.35001 -0.225044)
			(stroke
				(width 0.1)
				(type default)
			)
			(layer "F.Fab")
		)
		(fp_line
			(start -1.35001 -0.225044)
			(end -0.899922 -0.225044)
			(stroke
				(width 0.1)
				(type default)
			)
			(layer "F.Fab")
		)
		(fp_text user "-"
			(at 0.518922 -1.27635 180)
			(unlocked yes)
			(layer "F.SilkS")
			(effects
				(font
					(size 1.905 1.4224)
					(thickness 0.1524)
				)
				(justify left)
			)
		)
		(fp_text user "+"
			(at -2.808478 0.32385 180)
			(unlocked yes)
			(layer "F.SilkS")
			(effects
				(font
					(size 1.905 1.4224)
					(thickness 0.1524)
				)
				(justify left)
			)
		)
		(fp_text user "-"
			(at 1.8288 -0.24765 180)
			(unlocked yes)
			(layer "F.Fab")
			(effects
				(font
					(size 1.905 1.4224)
					(thickness 0.1524)
				)
				(justify left)
			)
		)
		(fp_text user "+"
			(at -2.794 -0.19685 180)
			(unlocked yes)
			(layer "F.Fab")
			(effects
				(font
					(size 1.905 1.4224)
					(thickness 0.1524)
				)
				(justify left)
			)
		)
		(pad "1" smd rect
			(at -1.0922 0)
			(size 0.8128 0.8636)
			(layers "F.Cu" "F.Mask" "F.Paste")
			(net "FAN_7_TACH_IL_R")
		)
		(pad "2" smd rect
			(at 1.0922 0 180)
			(size 0.8128 0.8636)
			(layers "F.Cu" "F.Mask" "F.Paste")
			(net "FAN_7_TACH_IL_D")
		)
	)
	(footprint ""
		(layer "F.Cu")
		(at 37.465 -250.19 180)
		(property "Reference" "PR29"
			(at 0 0 180)
			(layer "F.SilkS")
			(hide yes)
			(effects
				(font
					(size 1.27 1.27)
				)
			)
		)
		(property "Value" ""
			(at 0 0 180)
			(layer "F.Fab")
			(effects
				(font
					(size 1.27 1.27)
				)
			)
		)
		(duplicate_pad_numbers_are_jumpers no)
		(fp_line
			(start 0.7874 0.4064)
			(end -0.7874 0.4064)
			(stroke
				(width 0.1524)
				(type default)
			)
			(layer "F.SilkS")
		)
		(fp_line
			(start 0.7874 -0.4064)
			(end 0.7874 0.4064)
			(stroke
				(width 0.1524)
				(type default)
			)
			(layer "F.SilkS")
		)
		(fp_line
			(start -0.7874 0.4064)
			(end -0.7874 -0.4064)
			(stroke
				(width 0.1524)
				(type default)
			)
			(layer "F.SilkS")
		)
		(fp_line
			(start -0.7874 -0.4064)
			(end 0.7874 -0.4064)
			(stroke
				(width 0.1524)
				(type default)
			)
			(layer "F.SilkS")
		)
		(fp_line
			(start 0.67945 0.3048)
			(end 0.120396 0.3048)
			(stroke
				(width 0.1)
				(type default)
			)
			(layer "F.Fab")
		)
		(fp_line
			(start 0.67945 -0.3048)
			(end 0.67945 0.3048)
			(stroke
				(width 0.1)
				(type default)
			)
			(layer "F.Fab")
		)
		(fp_line
			(start 0.12065 -0.2794)
			(end 0.12065 -0.3048)
			(stroke
				(width 0.1)
				(type default)
			)
			(layer "F.Fab")
		)
		(fp_line
			(start 0.12065 -0.3048)
			(end 0.67945 -0.3048)
			(stroke
				(width 0.1)
				(type default)
			)
			(layer "F.Fab")
		)
		(fp_line
			(start 0.120396 0.3048)
			(end 0.120396 0.2794)
			(stroke
				(width 0.1)
				(type default)
			)
			(layer "F.Fab")
		)
		(fp_line
			(start 0.120396 0.2794)
			(end -0.12065 0.2794)
			(stroke
				(width 0.1)
				(type default)
			)
			(layer "F.Fab")
		)
		(fp_line
			(start -0.12065 0.3048)
			(end -0.67945 0.3048)
			(stroke
				(width 0.1)
				(type default)
			)
			(layer "F.Fab")
		)
		(fp_line
			(start -0.12065 0.2794)
			(end -0.12065 0.3048)
			(stroke
				(width 0.1)
				(type default)
			)
			(layer "F.Fab")
		)
		(fp_line
			(start -0.12065 -0.2794)
			(end 0.12065 -0.2794)
			(stroke
				(width 0.1)
				(type default)
			)
			(layer "F.Fab")
		)
		(fp_line
			(start -0.12065 -0.305054)
			(end -0.12065 -0.2794)
			(stroke
				(width 0.1)
				(type default)
			)
			(layer "F.Fab")
		)
		(fp_line
			(start -0.67945 0.3048)
			(end -0.67945 -0.305054)
			(stroke
				(width 0.1)
				(type default)
			)
			(layer "F.Fab")
		)
		(fp_line
			(start -0.67945 -0.305054)
			(end -0.12065 -0.305054)
			(stroke
				(width 0.1)
				(type default)
			)
			(layer "F.Fab")
		)
		(pad "1" smd circle
			(at -0.40005 0 180)
			(size 0 0)
			(layers "F.Cu" "F.Mask" "F.Paste")
			(net "FAN_1_P3V_R")
		)
		(pad "2" smd circle
			(at 0.40005 0 180)
			(size 0 0)
			(layers "F.Cu" "F.Mask" "F.Paste")
			(net "FAN_1_MODE")
		)
	)
)
